# T6G (Grand Teton) — schematic netlist excerpt (pin names and nets, part order shuffled) for the footprints in the layout excerpt that follows; sources: Cadence DE-HDL packaged netlist, KiCad conversion of 04192023_DAF0TMB3IC0_F0TG_MB_C_brd_V02_OCP.brd

R312  Q_RES  1K 1% CHIP  pkg 0402LF  page 107 : A = PWRGD_CHJ_CPU1_DIMM ; B = PWRGD_CHGL_CPU1
C1173  Q_CAP  0.1UF 16V 10% X7R  pkg C0402  page 83 : A = P3V3_AUX ; B = GND

(kicad_pcb
	(version 20260206)
	(generator "pcbnew")
	(generator_version "10.0")
	(general
		(thickness 1.6)
		(legacy_teardrops no)
	)
	(paper "A4")
	(title_block
		(title "04192023_DAF0TMB3IC0_F0TG_MB_C_brd_V02_OCP.brd")
		(comment 1 "Grand Teton / footprints 7162-7163 of 8354")
	)
	(layers
		(0 "F.Cu" signal "TOP")
		(4 "In1.Cu" signal "GND")
		(6 "In2.Cu" signal "IN1")
		(8 "In3.Cu" signal "GND1")
		(10 "In4.Cu" signal "IN2")
		(12 "In5.Cu" signal "GND2")
		(14 "In6.Cu" signal "IN3")
		(16 "In7.Cu" signal "GND3")
		(18 "In8.Cu" signal "VCC")
		(20 "In9.Cu" signal "VCC1")
		(22 "In10.Cu" signal "GND4")
		(24 "In11.Cu" signal "IN4")
		(26 "In12.Cu" signal "GND5")
		(28 "In13.Cu" signal "IN5")
		(30 "In14.Cu" signal "GND6")
		(32 "In15.Cu" signal "IN6")
		(34 "In16.Cu" signal "GND7")
		(2 "B.Cu" signal "BOTTOM")
		(9 "F.Adhes" user "F.Adhesive")
		(11 "B.Adhes" user "B.Adhesive")
		(13 "F.Paste" user "Package Geometry/Pastemask Top")
		(15 "B.Paste" user "Package Geometry/Pastemask Bottom")
		(5 "F.SilkS" user "Ref Des/Silkscreen Top")
		(7 "B.SilkS" user "Ref Des/Silkscreen Bottom")
		(1 "F.Mask" user "Board Geometry/Soldermask Top")
		(3 "B.Mask" user "Board Geometry/Soldermask Bottom")
		(17 "Dwgs.User" user "User.Drawings")
		(19 "Cmts.User" user "User.Comments")
		(21 "Eco1.User" user "User.Eco1")
		(23 "Eco2.User" user "User.Eco2")
		(25 "Edge.Cuts" user "Board Geometry/Outline")
		(27 "Margin" user)
		(31 "F.CrtYd" user "Package Geometry/Place Bound Top")
		(29 "B.CrtYd" user "Package Geometry/Place Bound Bottom")
		(35 "F.Fab" user "Ref Des/Assembly Top")
		(33 "B.Fab" user "Ref Des/Assembly Bottom")
	)
	(footprint ""
		(layer "B.Cu")
		(at 186.81446 -190.948564 180)
		(property "Reference" "R312"
			(at 0 0 0)
			(layer "B.SilkS")
			(hide yes)
			(effects
				(font
					(size 1.27 1.27)
				)
				(justify mirror)
			)
		)
		(property "Value" ""
			(at 0 0 0)
			(layer "B.Fab")
			(effects
				(font
					(size 1.27 1.27)
				)
				(justify mirror)
			)
		)
		(duplicate_pad_numbers_are_jumpers no)
		(fp_line
			(start 0.7874 0.4064)
			(end 0.7874 -0.4064)
			(stroke
				(width 0.1524)
				(type default)
			)
			(layer "B.SilkS")
		)
		(fp_line
			(start 0.7874 -0.4064)
			(end -0.7874 -0.4064)
			(stroke
				(width 0.1524)
				(type default)
			)
			(layer "B.SilkS")
		)
		(fp_line
			(start -0.7874 0.4064)
			(end 0.7874 0.4064)
			(stroke
				(width 0.1524)
				(type default)
			)
			(layer "B.SilkS")
		)
		(fp_line
			(start -0.7874 -0.4064)
			(end -0.7874 0.4064)
			(stroke
				(width 0.1524)
				(type default)
			)
			(layer "B.SilkS")
		)
		(fp_line
			(start 0.67945 0.3048)
			(end 0.67945 -0.305054)
			(stroke
				(width 0.1)
				(type default)
			)
			(layer "B.Fab")
		)
		(fp_line
			(start 0.67945 -0.305054)
			(end 0.12065 -0.305054)
			(stroke
				(width 0.1)
				(type default)
			)
			(layer "B.Fab")
		)
		(fp_line
			(start 0.12065 0.3048)
			(end 0.67945 0.3048)
			(stroke
				(width 0.1)
				(type default)
			)
			(layer "B.Fab")
		)
		(fp_line
			(start 0.12065 0.2794)
			(end 0.12065 0.3048)
			(stroke
				(width 0.1)
				(type default)
			)
			(layer "B.Fab")
		)
		(fp_line
			(start 0.12065 -0.2794)
			(end -0.12065 -0.2794)
			(stroke
				(width 0.1)
				(type default)
			)
			(layer "B.Fab")
		)
		(fp_line
			(start 0.12065 -0.305054)
			(end 0.12065 -0.2794)
			(stroke
				(width 0.1)
				(type default)
			)
			(layer "B.Fab")
		)
		(fp_line
			(start -0.120396 0.3048)
			(end -0.120396 0.2794)
			(stroke
				(width 0.1)
				(type default)
			)
			(layer "B.Fab")
		)
		(fp_line
			(start -0.120396 0.2794)
			(end 0.12065 0.2794)
			(stroke
				(width 0.1)
				(type default)
			)
			(layer "B.Fab")
		)
		(fp_line
			(start -0.12065 -0.2794)
			(end -0.12065 -0.3048)
			(stroke
				(width 0.1)
				(type default)
			)
			(layer "B.Fab")
		)
		(fp_line
			(start -0.12065 -0.3048)
			(end -0.67945 -0.3048)
			(stroke
				(width 0.1)
				(type default)
			)
			(layer "B.Fab")
		)
		(fp_line
			(start -0.67945 0.3048)
			(end -0.120396 0.3048)
			(stroke
				(width 0.1)
				(type default)
			)
			(layer "B.Fab")
		)
		(fp_line
			(start -0.67945 -0.3048)
			(end -0.67945 0.3048)
			(stroke
				(width 0.1)
				(type default)
			)
			(layer "B.Fab")
		)
		(pad "1" smd circle
			(at 0.40005 0)
			(size 0 0)
			(layers "B.Cu" "B.Mask" "B.Paste")
			(net "PWRGD_CHJ_CPU1_DIMM")
		)
		(pad "2" smd circle
			(at -0.40005 0)
			(size 0 0)
			(layers "B.Cu" "B.Mask" "B.Paste")
			(net "PWRGD_CHGL_CPU1")
		)
	)
	(footprint ""
		(layer "B.Cu")
		(at 185.458608 -116.642896 -90)
		(property "Reference" "C1173"
			(at 0 0 90)
			(layer "B.SilkS")
			(hide yes)
			(effects
				(font
					(size 1.27 1.27)
				)
				(justify mirror)
			)
		)
		(property "Value" ""
			(at 0 0 90)
			(layer "B.Fab")
			(effects
				(font
					(size 1.27 1.27)
				)
				(justify mirror)
			)
		)
		(duplicate_pad_numbers_are_jumpers no)
		(fp_line
			(start -0.69215 0.2921)
			(end 0.69215 0.2921)
			(stroke
				(width 0.1524)
				(type default)
			)
			(layer "B.SilkS")
		)
		(fp_line
			(start 0.69215 0.2921)
			(end 0.69215 -0.2921)
			(stroke
				(width 0.1524)
				(type default)
			)
			(layer "B.SilkS")
		)
		(fp_line
			(start -0.69215 -0.2921)
			(end -0.69215 0.2921)
			(stroke
				(width 0.1524)
				(type default)
			)
			(layer "B.SilkS")
		)
		(fp_line
			(start 0.69215 -0.2921)
			(end -0.69215 -0.2921)
			(stroke
				(width 0.1524)
				(type default)
			)
			(layer "B.SilkS")
		)
		(fp_line
			(start -0.51435 0.2794)
			(end 0.51435 0.2794)
			(stroke
				(width 0.1)
				(type default)
			)
			(layer "B.Fab")
		)
		(fp_line
			(start 0.51435 0.2794)
			(end 0.51435 -0.2794)
			(stroke
				(width 0.1)
				(type default)
			)
			(layer "B.Fab")
		)
		(fp_line
			(start -0.51435 -0.2794)
			(end -0.51435 0.2794)
			(stroke
				(width 0.1)
				(type default)
			)
			(layer "B.Fab")
		)
		(fp_line
			(start 0.51435 -0.2794)
			(end -0.51435 -0.2794)
			(stroke
				(width 0.1)
				(type default)
			)
			(layer "B.Fab")
		)
		(pad "1" smd circle
			(at 0.40005 0 90)
			(size 0 0)
			(layers "B.Cu" "B.Mask" "B.Paste")
			(net "P3V3_AUX")
		)
		(pad "2" smd circle
			(at -0.40005 0 90)
			(size 0 0)
			(layers "B.Cu" "B.Mask" "B.Paste")
			(net "GND")
		)
		(zone
			(layer "B.Cu")
			(hatch none 0.5)
			(connect_pads
				(clearance 0)
			)
			(min_thickness 0.25)
			(keepout
				(tracks not_allowed)
				(vias allowed)
				(pads allowed)
				(copperpour not_allowed)
				(footprints allowed)
			)
			(placement
				(enabled no)
				(sheetname "")
			)
			(fill
				(thermal_gap 0.5)
				(thermal_bridge_width 0.5)
				(island_removal_mode 0)
			)
			(polygon
				(pts
					(xy 185.312812 -116.543836) (xy 185.312812 -116.743226) (xy 185.370978 -116.833396) (xy 185.546238 -116.833396)
					(xy 185.604658 -116.743226) (xy 185.604658 -116.543836) (xy 185.546492 -116.452396) (xy 185.370978 -116.452396)
				)
			)
		)
	)
)
